G04*
G04 #@! TF.GenerationSoftware,Altium Limited,Altium Designer,23.6.0 (18)*
G04*
G04 Layer_Physical_Order=4*
G04 Layer_Color=16711680*
%FSLAX44Y44*%
%MOMM*%
G71*
G04*
G04 #@! TF.SameCoordinates,59133E90-4310-4D8A-9E2C-91A8D2F69FBB*
G04*
G04*
G04 #@! TF.FilePolarity,Positive*
G04*
G01*
G75*
%ADD13C,0.2032*%
%ADD52C,0.1778*%
%ADD53C,0.3048*%
%ADD54C,0.2540*%
%ADD56C,0.1905*%
%ADD58C,0.4064*%
%ADD60R,0.3500X1.9500*%
%ADD61C,6.0000*%
G36*
X215922Y265048D02*
X214748Y264562D01*
X211708Y267602D01*
X210973Y268093D01*
X210105Y268266D01*
X201000D01*
X200133Y268093D01*
X199398Y267602D01*
X169398Y237602D01*
X168906Y236867D01*
X168734Y236000D01*
Y157825D01*
X168906Y156958D01*
X169398Y156223D01*
X171559Y154061D01*
Y133907D01*
X170289Y133381D01*
X169870Y133799D01*
X168657Y134302D01*
X167343D01*
X166130Y133799D01*
X165596Y133266D01*
X116071D01*
X115898Y133231D01*
X113173Y133500D01*
X110386Y134345D01*
X107817Y135718D01*
X105566Y137566D01*
X104756Y138500D01*
X102842Y140834D01*
X100835Y144588D01*
X99599Y148663D01*
X99209Y152615D01*
X99266Y152900D01*
Y175757D01*
X99266Y175758D01*
X98840Y178995D01*
X97590Y182012D01*
X95602Y184602D01*
X95602Y184602D01*
X94874Y185571D01*
X94550Y186056D01*
X94232Y187655D01*
X94266Y187828D01*
Y302757D01*
X94237Y302905D01*
X94491Y304834D01*
X95293Y306770D01*
X96568Y308432D01*
X96568Y308432D01*
X96568Y308432D01*
X97567Y309203D01*
X98299Y309764D01*
X100318Y310600D01*
X102328Y310865D01*
X102484Y310834D01*
X207596D01*
X208130Y310301D01*
X209343Y309798D01*
X210657D01*
X211870Y310301D01*
X212799Y311230D01*
X213302Y312443D01*
Y313757D01*
X212799Y314970D01*
X211870Y315899D01*
X210657Y316402D01*
X209343D01*
X208130Y315899D01*
X207596Y315366D01*
X102484D01*
Y315369D01*
X99158Y314931D01*
X96058Y313647D01*
X93396Y311604D01*
X93398Y311602D01*
X91410Y309012D01*
X90160Y305995D01*
X89734Y302758D01*
X89734Y302757D01*
Y187828D01*
X89821Y187390D01*
X90072Y185482D01*
X90978Y183296D01*
X92418Y181418D01*
X92418D01*
X92444Y181417D01*
X93708Y179770D01*
X94509Y177834D01*
X94763Y175905D01*
X94734Y175757D01*
Y152900D01*
X94715D01*
X94981Y150199D01*
X93762Y149623D01*
X93701Y149683D01*
X92487Y150186D01*
X91174D01*
X89960Y149683D01*
X89031Y148754D01*
X88529Y147541D01*
Y146227D01*
X89031Y145013D01*
X89960Y144085D01*
X91174Y143582D01*
X92487D01*
X93701Y144085D01*
X94630Y145013D01*
X94690Y145158D01*
X96037Y145092D01*
X96708Y142879D01*
X99128Y138352D01*
X102384Y134384D01*
X102408Y134408D01*
X105336Y132004D01*
X107761Y130708D01*
X107443Y129438D01*
X79015D01*
X78481Y129972D01*
X77268Y130474D01*
X75954D01*
X74740Y129972D01*
X73812Y129043D01*
X73309Y127829D01*
Y126515D01*
X73812Y125302D01*
X74740Y124373D01*
X75954Y123870D01*
X77268D01*
X78481Y124373D01*
X79015Y124906D01*
X151889D01*
X153259Y123536D01*
X153171Y122965D01*
X152805Y122266D01*
X89000D01*
X88133Y122093D01*
X87398Y121602D01*
X80061Y114266D01*
X68404D01*
X67870Y114799D01*
X66657Y115302D01*
X65343D01*
X64130Y114799D01*
X63201Y113870D01*
X62698Y112657D01*
Y111343D01*
X63201Y110130D01*
X64130Y109201D01*
X65343Y108698D01*
X66657D01*
X67870Y109201D01*
X68404Y109734D01*
X78370D01*
X78856Y108561D01*
X72930Y102635D01*
X68392D01*
X67859Y103168D01*
X66645Y103671D01*
X65332D01*
X64118Y103168D01*
X63189Y102240D01*
X62686Y101026D01*
Y99712D01*
X63189Y98499D01*
X64118Y97570D01*
X65332Y97067D01*
X66645D01*
X67859Y97570D01*
X68392Y98103D01*
X73869D01*
X74736Y98275D01*
X75471Y98767D01*
X90245Y113540D01*
X90391Y113486D01*
X91491Y112875D01*
Y111696D01*
X43458Y63662D01*
X42966Y62927D01*
X42794Y62060D01*
Y34393D01*
X41435D01*
Y56000D01*
X41032Y56972D01*
X40060Y57375D01*
X18310D01*
X17338Y56972D01*
X16935Y56000D01*
Y34393D01*
X10137D01*
X10088Y34425D01*
X10088Y34425D01*
X8286Y35172D01*
X7699Y35289D01*
X7125Y35463D01*
X6150Y35559D01*
X5948Y35539D01*
X5750Y35578D01*
X4078D01*
X4078Y415922D01*
X215922D01*
X215922Y265048D01*
D02*
G37*
G36*
X212487Y250657D02*
Y241792D01*
X210097Y239402D01*
X209343D01*
X208130Y238899D01*
X207201Y237971D01*
X206698Y236757D01*
Y235443D01*
X207201Y234230D01*
X208130Y233301D01*
X209343Y232798D01*
X210657D01*
X211870Y233301D01*
X212799Y234230D01*
X213302Y235443D01*
Y236197D01*
X214748Y237644D01*
X215922Y237158D01*
Y220901D01*
X214748Y220415D01*
X213571Y221592D01*
X212836Y222083D01*
X211969Y222256D01*
X205990D01*
X205123Y222083D01*
X204387Y221592D01*
X195398Y212602D01*
X194907Y211867D01*
X194734Y211000D01*
Y207939D01*
X190398Y203602D01*
X189907Y202867D01*
X189734Y202000D01*
Y151939D01*
X183398Y145602D01*
X182906Y144867D01*
X182734Y144000D01*
Y90939D01*
X174061Y82266D01*
X164242D01*
X163512Y83443D01*
X163524Y83536D01*
X164176Y83972D01*
X178602Y98398D01*
X179093Y99133D01*
X179266Y100000D01*
X179266Y100000D01*
Y219232D01*
X211217Y251183D01*
X212487Y250657D01*
D02*
G37*
G36*
X210229Y262672D02*
X209703Y261402D01*
X209343D01*
X208130Y260899D01*
X207201Y259970D01*
X206698Y258757D01*
Y257443D01*
X207201Y256230D01*
X207734Y255696D01*
Y254109D01*
X175398Y221773D01*
X174907Y221038D01*
X174734Y220171D01*
Y160268D01*
X173464Y159589D01*
X173266Y159722D01*
Y235061D01*
X201939Y263734D01*
X209167D01*
X210229Y262672D01*
D02*
G37*
G36*
X212330Y210117D02*
Y208635D01*
X210097Y206402D01*
X209343D01*
X208130Y205899D01*
X207201Y204970D01*
X206698Y203757D01*
Y202443D01*
X207201Y201230D01*
X208130Y200301D01*
X209343Y199798D01*
X210657D01*
X211870Y200301D01*
X212799Y201230D01*
X213302Y202443D01*
Y203197D01*
X214748Y204644D01*
X215922Y204158D01*
X215922Y57517D01*
X214652Y56677D01*
X193657D01*
X192685Y56274D01*
X192282Y55302D01*
Y45051D01*
X192387Y44798D01*
Y44525D01*
X192472Y44319D01*
Y43552D01*
X192387Y43346D01*
Y43072D01*
X192282Y42820D01*
Y39013D01*
X192282Y39013D01*
X192529Y38416D01*
Y38344D01*
X192927Y37383D01*
Y36617D01*
X192529Y35656D01*
Y35584D01*
X192282Y34987D01*
X191217Y34393D01*
X174673D01*
X174123Y35217D01*
X172467Y36872D01*
X171144Y37757D01*
X171144Y37757D01*
X168981Y38652D01*
X168981Y38653D01*
X167421Y38963D01*
X165079D01*
X163519Y38653D01*
X163519Y38652D01*
X161356Y37757D01*
X160033Y36872D01*
X158377Y35217D01*
X157826Y34393D01*
X107326D01*
Y43121D01*
X130939Y66734D01*
X171000D01*
X171867Y66906D01*
X172602Y67398D01*
X191602Y86398D01*
X192094Y87133D01*
X192266Y88000D01*
Y110805D01*
X192965Y111171D01*
X193536Y111259D01*
X195398Y109398D01*
X196133Y108906D01*
X197000Y108734D01*
X201596D01*
X202130Y108201D01*
X203343Y107698D01*
X204657D01*
X205870Y108201D01*
X206799Y109130D01*
X207302Y110343D01*
Y111657D01*
X206799Y112870D01*
X205870Y113799D01*
X204657Y114302D01*
X203343D01*
X202130Y113799D01*
X201596Y113266D01*
X197939D01*
X197266Y113939D01*
Y117320D01*
X198536Y117794D01*
X199130Y117201D01*
X200343Y116698D01*
X201657D01*
X202870Y117201D01*
X203799Y118130D01*
X204302Y119343D01*
Y120657D01*
X203799Y121870D01*
X203266Y122404D01*
Y131061D01*
X211602Y139398D01*
X212094Y140133D01*
X212266Y141000D01*
Y178696D01*
X212799Y179230D01*
X213302Y180443D01*
Y181757D01*
X212799Y182971D01*
X211870Y183899D01*
X210657Y184402D01*
X209343D01*
X208536Y184068D01*
X207266Y184695D01*
Y186161D01*
X209903Y188798D01*
X210657D01*
X211870Y189301D01*
X212799Y190230D01*
X213302Y191443D01*
Y192757D01*
X212799Y193971D01*
X211870Y194899D01*
X210657Y195402D01*
X209343D01*
X208130Y194899D01*
X207201Y193971D01*
X206698Y192757D01*
Y192003D01*
X203398Y188702D01*
X202906Y187967D01*
X202734Y187100D01*
Y143939D01*
X193536Y134741D01*
X192965Y134829D01*
X192266Y135195D01*
Y143061D01*
X197602Y148398D01*
X197602Y148398D01*
X198094Y149133D01*
X198266Y150000D01*
X198266Y150000D01*
Y199161D01*
X209903Y210798D01*
X210657D01*
X211060Y210965D01*
X212330Y210117D01*
D02*
G37*
G36*
X174734Y124870D02*
Y100939D01*
X161635Y87840D01*
X92566D01*
X92033Y88373D01*
X90819Y88876D01*
X89506D01*
X88292Y88373D01*
X87363Y87444D01*
X86861Y86231D01*
Y84917D01*
X87363Y83704D01*
X88292Y82775D01*
X89506Y82272D01*
X90819D01*
X92033Y82775D01*
X92566Y83308D01*
X135022D01*
X135752Y82131D01*
X135739Y82038D01*
X135087Y81602D01*
X131481Y77996D01*
X130730D01*
X129863Y77823D01*
X129127Y77332D01*
X98458Y46662D01*
X97966Y45927D01*
X97794Y45060D01*
Y34393D01*
X89266D01*
Y48000D01*
X89215Y48258D01*
X89600Y51185D01*
X90829Y54152D01*
X92625Y56492D01*
X92843Y56638D01*
X95604Y59399D01*
X95651Y59470D01*
X96485Y60027D01*
X97470Y60223D01*
X97554Y60206D01*
X104545D01*
X105078Y59673D01*
X106292Y59170D01*
X107605D01*
X108819Y59673D01*
X109748Y60602D01*
X110250Y61815D01*
Y63129D01*
X109748Y64343D01*
X108819Y65272D01*
X107605Y65774D01*
X106292D01*
X105078Y65272D01*
X104545Y64738D01*
X97554D01*
X96885Y64605D01*
X95679Y64446D01*
X93931Y63722D01*
X92971Y62986D01*
X92400Y62604D01*
X89638Y59843D01*
X89486Y59616D01*
X87579Y57292D01*
X86034Y54400D01*
X85082Y51263D01*
X84786Y48264D01*
X84734Y48000D01*
Y34393D01*
X82296D01*
Y48644D01*
X82361Y48970D01*
X82266Y49446D01*
Y64768D01*
X82382Y64817D01*
X83311Y65745D01*
X83814Y66959D01*
Y68273D01*
X83311Y69486D01*
X82382Y70415D01*
X81169Y70918D01*
X79855D01*
X78642Y70415D01*
X77713Y69486D01*
X77210Y68273D01*
Y66959D01*
X77713Y65745D01*
X77734Y65724D01*
Y49325D01*
X77669Y49000D01*
X77764Y48524D01*
Y34393D01*
X52326D01*
Y56189D01*
X85871Y89734D01*
X87000D01*
X87867Y89906D01*
X88602Y90398D01*
X91412Y93207D01*
X91903Y93943D01*
X92076Y94810D01*
Y97259D01*
X93111Y98293D01*
X93714D01*
X94927Y98796D01*
X95856Y99725D01*
X96359Y100939D01*
Y102252D01*
X95856Y103466D01*
X94927Y104395D01*
X93714Y104897D01*
X92898D01*
X92352Y106147D01*
X95121Y108917D01*
X95450D01*
X96664Y109419D01*
X97593Y110348D01*
X98095Y111562D01*
Y112875D01*
X98059Y112964D01*
X98907Y114234D01*
X160561D01*
X162698Y112097D01*
Y111343D01*
X163201Y110130D01*
X164130Y109201D01*
X165343Y108698D01*
X166657D01*
X167870Y109201D01*
X168799Y110130D01*
X169302Y111343D01*
Y112657D01*
X168799Y113870D01*
X167870Y114799D01*
X166808Y115239D01*
X166657Y115428D01*
X166717Y115738D01*
X167482Y116698D01*
X167657D01*
X168870Y117201D01*
X169799Y118130D01*
X170302Y119343D01*
Y120657D01*
X169968Y121464D01*
X169972Y121644D01*
X170387Y122584D01*
X170610Y122855D01*
X170867Y122907D01*
X171602Y123398D01*
X173561Y125356D01*
X174734Y124870D01*
D02*
G37*
G36*
X215000Y36000D02*
X207000Y34000D01*
X205000Y31000D01*
X193657D01*
Y34987D01*
X193799Y35130D01*
X194302Y36343D01*
Y37657D01*
X193799Y38870D01*
X193657Y39013D01*
Y42820D01*
X193847Y43278D01*
Y44592D01*
X193657Y45051D01*
Y55302D01*
X215000D01*
Y36000D01*
D02*
G37*
G36*
X40060Y28000D02*
X18310D01*
Y56000D01*
X40060D01*
Y28000D01*
D02*
G37*
%LPC*%
G36*
X37000Y412138D02*
X25795D01*
X24928Y411965D01*
X24193Y411474D01*
X17528Y404809D01*
X16774D01*
X15560Y404306D01*
X14631Y403377D01*
X14128Y402164D01*
Y400850D01*
X14631Y399637D01*
X15560Y398708D01*
X16774Y398205D01*
X18087D01*
X19301Y398708D01*
X19368Y398775D01*
X19995Y398969D01*
X21120Y398070D01*
Y388614D01*
X21293Y387747D01*
X21784Y387011D01*
X50311Y358484D01*
X51046Y357993D01*
X51089Y357985D01*
X51175Y357779D01*
X52104Y356850D01*
X52861Y356536D01*
X52609Y355266D01*
X26000D01*
X25133Y355093D01*
X24398Y354602D01*
X23907Y353867D01*
X23734Y353000D01*
Y351404D01*
X23201Y350870D01*
X22698Y349657D01*
Y348343D01*
X23201Y347130D01*
X23572Y346758D01*
X23046Y345488D01*
X21474D01*
X21318Y345865D01*
X20389Y346794D01*
X19176Y347296D01*
X17862D01*
X16648Y346794D01*
X15720Y345865D01*
X14397Y345784D01*
X14186Y345964D01*
X13799Y347130D01*
X14302Y348343D01*
Y349657D01*
X13799Y350870D01*
X12870Y351799D01*
X11657Y352302D01*
X10343D01*
X9130Y351799D01*
X8201Y350870D01*
X7698Y349657D01*
Y348343D01*
X8201Y347130D01*
X9130Y346201D01*
X9171Y346183D01*
Y344638D01*
X9344Y343771D01*
X9610Y343373D01*
X9456Y342284D01*
X9233Y341842D01*
X9130Y341799D01*
X8201Y340870D01*
X7698Y339657D01*
Y338343D01*
X8201Y337130D01*
X9130Y336201D01*
X10343Y335698D01*
X11657D01*
X12870Y336201D01*
X13799Y337130D01*
X13842Y337233D01*
X15340Y337531D01*
X20441Y332429D01*
X21176Y331938D01*
X22043Y331766D01*
X124505D01*
X125039Y331232D01*
X126252Y330730D01*
X127566D01*
X128779Y331232D01*
X129708Y332161D01*
X130211Y333375D01*
Y334688D01*
X129708Y335902D01*
X128779Y336831D01*
X127566Y337334D01*
X126252D01*
X125039Y336831D01*
X124505Y336298D01*
X22982D01*
X19732Y339548D01*
X19780Y340398D01*
X20120Y340956D01*
X41000D01*
X41867Y341128D01*
X42602Y341620D01*
X43094Y342355D01*
X43266Y343222D01*
Y345734D01*
X48548D01*
X48801Y344464D01*
X48045Y344151D01*
X47116Y343222D01*
X46613Y342008D01*
Y340695D01*
X47116Y339481D01*
X48045Y338552D01*
X49258Y338050D01*
X50572D01*
X51786Y338552D01*
X52431Y339197D01*
X52862Y339482D01*
X54094Y339494D01*
X54225Y339407D01*
X55092Y339234D01*
X128698D01*
X134521Y333411D01*
Y332657D01*
X135023Y331443D01*
X135952Y330514D01*
X137166Y330012D01*
X138480D01*
X139693Y330514D01*
X140622Y331443D01*
X141125Y332657D01*
Y333970D01*
X140622Y335184D01*
X139693Y336113D01*
X138480Y336616D01*
X137725D01*
X131239Y343102D01*
X130698Y343464D01*
X130755Y344301D01*
X130909Y344734D01*
X141061D01*
X146758Y339038D01*
Y336579D01*
X146224Y336046D01*
X145722Y334832D01*
Y333518D01*
X146224Y332305D01*
X147153Y331376D01*
X148367Y330873D01*
X149680D01*
X150894Y331376D01*
X151823Y332305D01*
X152326Y333518D01*
Y334832D01*
X151823Y336046D01*
X151290Y336579D01*
Y339976D01*
X151117Y340844D01*
X150626Y341579D01*
X143602Y348602D01*
X142867Y349094D01*
X142000Y349266D01*
X65005D01*
Y353000D01*
X64833Y353867D01*
X64342Y354602D01*
X63607Y355093D01*
X62739Y355266D01*
X55339D01*
X55087Y356536D01*
X55844Y356850D01*
X56773Y357779D01*
X57276Y358992D01*
Y360306D01*
X56773Y361520D01*
X55844Y362449D01*
X54631Y362951D01*
X53317D01*
X52565Y362640D01*
X25652Y389552D01*
Y398619D01*
X26186Y399152D01*
X26688Y400366D01*
Y401680D01*
X26186Y402893D01*
X25257Y403822D01*
X24896Y403972D01*
X24598Y405470D01*
X26734Y407606D01*
X30141D01*
X30394Y406336D01*
X29543Y405984D01*
X28614Y405055D01*
X28112Y403841D01*
Y402527D01*
X28614Y401314D01*
X29543Y400385D01*
X30757Y399882D01*
X32071D01*
X33284Y400385D01*
X34213Y401314D01*
X34716Y402527D01*
Y403841D01*
X34213Y405055D01*
X33284Y405984D01*
X32434Y406336D01*
X32687Y407606D01*
X36061D01*
X41983Y401684D01*
X42718Y401193D01*
X43585Y401021D01*
X43585Y401021D01*
X66310D01*
X66843Y400487D01*
X68057Y399985D01*
X69370D01*
X70584Y400487D01*
X71513Y401416D01*
X72015Y402630D01*
Y403943D01*
X71513Y405157D01*
X70584Y406086D01*
X69370Y406589D01*
X68057D01*
X66843Y406086D01*
X66310Y405553D01*
X44524D01*
X38602Y411474D01*
X37867Y411965D01*
X37000Y412138D01*
D02*
G37*
G36*
X40480Y365157D02*
X39167D01*
X37953Y364655D01*
X37024Y363726D01*
X36521Y362512D01*
Y361198D01*
X37024Y359985D01*
X37953Y359056D01*
X39167Y358553D01*
X40480D01*
X41694Y359056D01*
X42623Y359985D01*
X43126Y361198D01*
Y362512D01*
X42623Y363726D01*
X41694Y364655D01*
X40480Y365157D01*
D02*
G37*
G36*
X210657Y305402D02*
X209343D01*
X208130Y304899D01*
X207201Y303971D01*
X206698Y302757D01*
Y302003D01*
X205737Y301042D01*
X205562Y300780D01*
X202283Y298088D01*
X198267Y295942D01*
X193910Y294620D01*
X189688Y294205D01*
X189379Y294266D01*
X142828D01*
X142390Y294179D01*
X140482Y293928D01*
X138296Y293022D01*
X136769Y291851D01*
X136398Y291602D01*
X134837Y290042D01*
X134734Y289888D01*
X132035Y286728D01*
X129769Y283029D01*
X128109Y279021D01*
X127096Y274804D01*
X126770Y270660D01*
X126734Y270479D01*
Y155532D01*
X126787Y155263D01*
X126390Y152240D01*
X125119Y149173D01*
X123263Y146755D01*
X123035Y146602D01*
X119607Y143174D01*
X119546Y143082D01*
X118276Y142108D01*
X117064Y141606D01*
X116870Y141799D01*
X115657Y142302D01*
X114343D01*
X113130Y141799D01*
X112201Y140870D01*
X111698Y139657D01*
Y138343D01*
X112201Y137130D01*
X113130Y136201D01*
X114343Y135698D01*
X115657D01*
X116870Y136201D01*
X117783Y137113D01*
X117856Y137123D01*
X120518Y138225D01*
X122653Y139864D01*
X122812Y139970D01*
X126240Y143398D01*
X126378Y143605D01*
X128354Y146012D01*
X129937Y148974D01*
X130912Y152189D01*
X131217Y155288D01*
X131266Y155532D01*
Y270479D01*
X131205Y270788D01*
X131620Y275010D01*
X132942Y279367D01*
X135088Y283382D01*
X137780Y286662D01*
X138042Y286837D01*
X139602Y288398D01*
X139701Y288545D01*
X141056Y289450D01*
X142655Y289769D01*
X142828Y289734D01*
X189379D01*
X189560Y289770D01*
X193703Y290096D01*
X197921Y291109D01*
X201929Y292769D01*
X205628Y295035D01*
X208788Y297734D01*
X208942Y297837D01*
X209903Y298798D01*
X210657D01*
X211870Y299301D01*
X212799Y300230D01*
X213302Y301443D01*
Y302757D01*
X212799Y303971D01*
X211870Y304899D01*
X210657Y305402D01*
D02*
G37*
G36*
X106834Y150302D02*
X105521D01*
X104307Y149799D01*
X103378Y148870D01*
X102876Y147657D01*
Y146343D01*
X103378Y145130D01*
X104307Y144201D01*
X105521Y143698D01*
X106834D01*
X108048Y144201D01*
X108977Y145130D01*
X109480Y146343D01*
Y147657D01*
X108977Y148870D01*
X108048Y149799D01*
X106834Y150302D01*
D02*
G37*
G36*
X52759Y142744D02*
X51445D01*
X50232Y142241D01*
X49303Y141313D01*
X48800Y140099D01*
Y138785D01*
X49303Y137572D01*
X50232Y136643D01*
X51445Y136140D01*
X52759D01*
X53972Y136643D01*
X54901Y137572D01*
X55404Y138785D01*
Y140099D01*
X54901Y141313D01*
X53972Y142241D01*
X52759Y142744D01*
D02*
G37*
G36*
X128871Y141302D02*
X127558D01*
X126344Y140799D01*
X125415Y139870D01*
X124912Y138657D01*
Y137343D01*
X125415Y136130D01*
X126344Y135201D01*
X127558Y134698D01*
X128871D01*
X130085Y135201D01*
X131014Y136130D01*
X131516Y137343D01*
Y138657D01*
X131014Y139870D01*
X130085Y140799D01*
X128871Y141302D01*
D02*
G37*
G36*
X42449Y120544D02*
X41135D01*
X39922Y120041D01*
X38993Y119112D01*
X38490Y117898D01*
Y116585D01*
X38993Y115371D01*
X39922Y114442D01*
X41135Y113940D01*
X42449D01*
X43663Y114442D01*
X44591Y115371D01*
X45094Y116585D01*
Y117898D01*
X44591Y119112D01*
X43663Y120041D01*
X42449Y120544D01*
D02*
G37*
G36*
X38415Y76302D02*
X37101D01*
X35887Y75799D01*
X34959Y74870D01*
X34456Y73657D01*
Y72343D01*
X34959Y71130D01*
X35887Y70201D01*
X37101Y69698D01*
X38415D01*
X39628Y70201D01*
X40557Y71130D01*
X41060Y72343D01*
Y73657D01*
X40557Y74870D01*
X39628Y75799D01*
X38415Y76302D01*
D02*
G37*
G36*
X37657Y67302D02*
X36343D01*
X35130Y66799D01*
X34201Y65870D01*
X33698Y64657D01*
Y63343D01*
X34201Y62130D01*
X35130Y61201D01*
X36343Y60698D01*
X37657D01*
X38870Y61201D01*
X39799Y62130D01*
X40302Y63343D01*
Y64657D01*
X39799Y65870D01*
X38870Y66799D01*
X37657Y67302D01*
D02*
G37*
%LPD*%
D13*
X80030Y15280D02*
X80060Y15250D01*
X80000Y49000D02*
X80030Y48970D01*
D52*
X97000Y152900D02*
G03*
X104000Y136000I23899J0D01*
G01*
D02*
G03*
X116071Y131000I12071J12071D01*
G01*
X124638Y145000D02*
G03*
X129000Y155532I-10532J10532D01*
G01*
X115000Y139000D02*
G03*
X121210Y141572I0J8782D01*
G01*
X92000Y187828D02*
G03*
X94000Y183000I6828J0D01*
G01*
X97000Y175757D02*
G03*
X94000Y183000I-10243J0D01*
G01*
X102484Y313100D02*
G03*
X95000Y310000I0J-10584D01*
G01*
D02*
G03*
X92000Y302757I7243J-7243D01*
G01*
X189379Y292000D02*
G03*
X207339Y299440I0J25400D01*
G01*
X142828Y292000D02*
G03*
X138000Y290000I0J-6828D01*
G01*
X136440Y288440D02*
G03*
X129000Y270479I17960J-17960D01*
G01*
X87000Y31711D02*
G03*
X88756Y27473I5994J0D01*
G01*
X91240Y58240D02*
G03*
X87000Y48000I10245J-10240D01*
G01*
X91243Y58243D02*
G03*
X91240Y58240I10243J-10243D01*
G01*
X94002Y61002D02*
G03*
X94000Y61000I3553J-3556D01*
G01*
X97554Y62472D02*
G03*
X94002Y61002I0J-5027D01*
G01*
D53*
X205985Y33450D02*
X211156Y38620D01*
X203450Y33450D02*
X205985D01*
X200060Y30060D02*
X203450Y33450D01*
X195060Y31114D02*
X204000Y40054D01*
X195060Y15250D02*
Y31114D01*
X200060Y15250D02*
Y30060D01*
D54*
X20060Y15250D02*
Y30000D01*
X25060Y15250D02*
Y32027D01*
X30060Y15250D02*
Y31802D01*
D56*
X90060Y24324D02*
G03*
X88756Y27473I-4453J0D01*
G01*
X11437Y344638D02*
Y347036D01*
X22043Y334032D02*
X126909D01*
X11437Y344638D02*
X22043Y334032D01*
X11413Y347060D02*
X11437Y347036D01*
X11413Y347060D02*
Y348587D01*
X11000Y349000D02*
X11413Y348587D01*
X211969Y219990D02*
X214596Y217362D01*
X197000Y211000D02*
X205990Y219990D01*
X211969D01*
X210000Y203100D02*
X214596Y207696D01*
Y217362D01*
X210105Y266000D02*
X214753Y261353D01*
Y240853D02*
Y261353D01*
X210000Y236100D02*
X214753Y240853D01*
X171000Y69000D02*
X190000Y88000D01*
X130000Y69000D02*
X171000D01*
X105060Y44060D02*
X130000Y69000D01*
X195000Y113000D02*
Y133000D01*
X197000Y111000D02*
X204000D01*
X195000Y113000D02*
X197000Y111000D01*
X170000Y125000D02*
X173825Y128825D01*
X171000Y157825D02*
Y236000D01*
Y157825D02*
X173825Y155000D01*
Y128825D02*
Y155000D01*
X62739Y347000D02*
X142000D01*
X26000Y353000D02*
X62739D01*
Y347000D02*
Y353000D01*
X26000Y349000D02*
Y353000D01*
X18519Y343222D02*
X41000D01*
Y348000D01*
X55092D01*
X18519Y343222D02*
Y343994D01*
X55092Y341500D02*
X129636D01*
X55092D02*
Y348000D01*
X142000Y347000D02*
X149024Y339976D01*
Y334175D02*
Y339976D01*
X171000Y236000D02*
X201000Y266000D01*
X210105D01*
X155000Y125000D02*
X170000D01*
X76611Y127172D02*
X152828D01*
X155000Y125000D01*
X162574Y85574D02*
X177000Y100000D01*
Y220171D02*
X210000Y253171D01*
X177000Y100000D02*
Y220171D01*
X210000Y253171D02*
Y258100D01*
X90162Y85574D02*
X162574D01*
X97000Y152900D02*
Y175757D01*
X116071Y131000D02*
X168000D01*
X129000Y155532D02*
Y270479D01*
X121210Y141572D02*
X124638Y145000D01*
X185000Y90000D02*
Y144000D01*
X175000Y80000D02*
X185000Y90000D01*
Y144000D02*
X192000Y151000D01*
X190000Y88000D02*
Y144000D01*
X196000Y150000D01*
X92000Y187828D02*
Y302757D01*
X102484Y313100D02*
X210000D01*
X207339Y299440D02*
X210000Y302100D01*
X142828Y292000D02*
X189379D01*
X136440Y288440D02*
X138000Y290000D01*
X94793Y111793D02*
Y112219D01*
X45060Y62060D02*
X94793Y111793D01*
X45060Y15250D02*
Y62060D01*
X93057Y101444D02*
Y101595D01*
X89810Y98197D02*
X93057Y101444D01*
X89810Y94810D02*
Y98197D01*
X87000Y92000D02*
X89810Y94810D01*
X50060Y57128D02*
X84932Y92000D01*
X87000D01*
X50060Y15250D02*
Y57128D01*
X205000Y187100D02*
X210000Y192100D01*
X205000Y143000D02*
Y187100D01*
X195000Y133000D02*
X205000Y143000D01*
X210000Y141000D02*
Y181100D01*
X201000Y132000D02*
X210000Y141000D01*
X201000Y120000D02*
Y132000D01*
X90000Y116500D02*
X161500D01*
X166000Y112000D01*
X65988Y100369D02*
X73869D01*
X90000Y116500D01*
X89000Y120000D02*
X167000D01*
X81000Y112000D02*
X89000Y120000D01*
X66000Y112000D02*
X81000D01*
X100060Y45060D02*
X130730Y75730D01*
X197000Y207000D02*
Y211000D01*
X192000Y151000D02*
Y202000D01*
X197000Y207000D01*
X136690Y80000D02*
X175000D01*
X130730Y75730D02*
X132419D01*
X136690Y80000D01*
X196000Y150000D02*
Y200100D01*
X210000Y214100D01*
X100060Y15250D02*
Y45060D01*
X105060Y15250D02*
Y44060D01*
X80000Y67104D02*
X80512Y67616D01*
X80000Y49000D02*
Y67104D01*
X87000Y31711D02*
Y48000D01*
X94000Y61000D02*
X94002Y61002D01*
X91243Y58243D02*
X94000Y61000D01*
X91240Y58240D02*
X91243Y58243D01*
X97554Y62472D02*
X106948D01*
X129636Y341500D02*
X137823Y333314D01*
X17430Y401507D02*
X25795Y409872D01*
X37000D01*
X43585Y403287D02*
X68713D01*
X37000Y409872D02*
X43585Y403287D01*
X53537Y360087D02*
X53974Y359649D01*
X51913Y360087D02*
X53537D01*
X23386Y388614D02*
X51913Y360087D01*
X23386Y388614D02*
Y401023D01*
X90060Y15250D02*
Y24324D01*
X80030Y15280D02*
Y48970D01*
D58*
X211156Y38620D02*
D03*
X126000Y100000D02*
D03*
X104000Y107000D02*
D03*
X209830Y407680D02*
D03*
Y397520D02*
D03*
Y387360D02*
D03*
Y377200D02*
D03*
Y367040D02*
D03*
Y356880D02*
D03*
Y346720D02*
D03*
Y336560D02*
D03*
Y326400D02*
D03*
X199670Y407680D02*
D03*
Y397520D02*
D03*
Y387360D02*
D03*
Y377200D02*
D03*
Y367040D02*
D03*
Y356880D02*
D03*
Y346720D02*
D03*
Y336560D02*
D03*
Y326400D02*
D03*
X189510Y387360D02*
D03*
Y367040D02*
D03*
Y356880D02*
D03*
Y346720D02*
D03*
Y336560D02*
D03*
Y326400D02*
D03*
X179350Y367040D02*
D03*
Y356880D02*
D03*
Y346720D02*
D03*
Y336560D02*
D03*
X169190Y407680D02*
D03*
X159030Y387360D02*
D03*
Y377200D02*
D03*
Y356880D02*
D03*
Y346720D02*
D03*
Y336560D02*
D03*
X148870Y387360D02*
D03*
Y346720D02*
D03*
X138710Y397520D02*
D03*
Y387360D02*
D03*
X128550D02*
D03*
X118390D02*
D03*
X98070D02*
D03*
X87910Y306080D02*
D03*
X77750Y407680D02*
D03*
Y387360D02*
D03*
Y356880D02*
D03*
X67590Y397520D02*
D03*
Y306080D02*
D03*
Y295920D02*
D03*
Y285760D02*
D03*
Y275600D02*
D03*
X190545Y43935D02*
D03*
X115000Y146000D02*
D03*
X106178Y147000D02*
D03*
X115000Y139000D02*
D03*
X168000Y131000D02*
D03*
X204000Y111000D02*
D03*
X166000Y112000D02*
D03*
X201000Y120000D02*
D03*
X167000D02*
D03*
X154373Y105997D02*
D03*
X210000Y181100D02*
D03*
Y192100D02*
D03*
X76611Y127172D02*
D03*
X52102Y139442D02*
D03*
X53051Y126729D02*
D03*
X41792Y117242D02*
D03*
X39452Y130651D02*
D03*
X12000Y65000D02*
D03*
Y74000D02*
D03*
X37758Y73000D02*
D03*
X37000Y64000D02*
D03*
X206000Y52000D02*
D03*
X197000D02*
D03*
X207000Y77000D02*
D03*
X198000D02*
D03*
X204000Y40054D02*
D03*
X191000Y37000D02*
D03*
X90162Y85574D02*
D03*
X80512Y67616D02*
D03*
X106948Y62472D02*
D03*
X93057Y101595D02*
D03*
X94793Y112219D02*
D03*
X65988Y100369D02*
D03*
X66000Y112000D02*
D03*
X145027Y145180D02*
D03*
X128214Y138000D02*
D03*
X181826Y161442D02*
D03*
X148849Y161221D02*
D03*
X138262Y162104D02*
D03*
X83228D02*
D03*
X83000Y146000D02*
D03*
X91831Y146884D02*
D03*
X37000Y194600D02*
D03*
X58000D02*
D03*
X79000D02*
D03*
X100000Y194000D02*
D03*
X121000Y194600D02*
D03*
X142000D02*
D03*
X163000D02*
D03*
X184000Y194600D02*
D03*
X37000Y215600D02*
D03*
X58000D02*
D03*
X79000D02*
D03*
X100000Y215000D02*
D03*
X121000Y215600D02*
D03*
X142000D02*
D03*
X163000D02*
D03*
X184000Y215600D02*
D03*
X37000Y236600D02*
D03*
X58000D02*
D03*
X79000D02*
D03*
X100000Y236000D02*
D03*
X121000Y236600D02*
D03*
X142000D02*
D03*
X163000D02*
D03*
X184000Y236600D02*
D03*
X37000Y257000D02*
D03*
X58000D02*
D03*
X79000D02*
D03*
X100000Y256400D02*
D03*
X121000Y257000D02*
D03*
X142000D02*
D03*
X163000D02*
D03*
X184000Y257000D02*
D03*
X37000Y278600D02*
D03*
X58000D02*
D03*
X79000D02*
D03*
X100000Y278000D02*
D03*
X121000Y278600D02*
D03*
X142000D02*
D03*
X163000D02*
D03*
X184000Y278600D02*
D03*
Y299600D02*
D03*
X163000Y299600D02*
D03*
X142000D02*
D03*
X121000D02*
D03*
X100000Y299000D02*
D03*
X79000Y299600D02*
D03*
X58000D02*
D03*
X37000D02*
D03*
X210000Y203100D02*
D03*
Y214100D02*
D03*
Y236100D02*
D03*
Y258100D02*
D03*
Y302100D02*
D03*
Y313100D02*
D03*
X149024Y334175D02*
D03*
X137823Y333314D02*
D03*
X126909Y334032D02*
D03*
X17430Y401507D02*
D03*
X68713Y403287D02*
D03*
X14291Y409878D02*
D03*
X11151Y401828D02*
D03*
X53974Y359649D02*
D03*
X23386Y401023D02*
D03*
X51000Y371000D02*
D03*
X50396Y377474D02*
D03*
X31414Y403184D02*
D03*
X11000Y339000D02*
D03*
X18519Y343994D02*
D03*
X26000Y349000D02*
D03*
X11000D02*
D03*
X49915Y341352D02*
D03*
X39824Y361855D02*
D03*
X63000Y38000D02*
D03*
X176000Y44000D02*
D03*
X111000Y35000D02*
D03*
X152000Y36000D02*
D03*
X137000D02*
D03*
X123000Y35000D02*
D03*
X93000Y34000D02*
D03*
X33000Y31000D02*
D03*
Y38000D02*
D03*
X32880Y45166D02*
D03*
X33000Y51645D02*
D03*
X15000Y50312D02*
D03*
X12791Y42000D02*
D03*
X6395Y41971D02*
D03*
X6826Y50312D02*
D03*
D60*
X140060Y15250D02*
D03*
X135060D02*
D03*
X130060D02*
D03*
X125060D02*
D03*
X120060D02*
D03*
X115060D02*
D03*
X110060D02*
D03*
X155060D02*
D03*
X150060D02*
D03*
X80060D02*
D03*
X90060D02*
D03*
X85060D02*
D03*
X95060D02*
D03*
X75060D02*
D03*
X70060D02*
D03*
X65060D02*
D03*
X60060D02*
D03*
X55060D02*
D03*
X50060D02*
D03*
X45060D02*
D03*
X40060D02*
D03*
X35060D02*
D03*
X30060D02*
D03*
X25060D02*
D03*
X100060D02*
D03*
X105060D02*
D03*
X145060D02*
D03*
X185060D02*
D03*
X200060D02*
D03*
X195060D02*
D03*
X190060D02*
D03*
X180060D02*
D03*
X20060D02*
D03*
D61*
X110000Y420000D02*
D03*
M02*
